# T6G (Grand Teton) — schematic netlist excerpt (pin names and nets, part order shuffled) for the footprints in the layout excerpt that follows; sources: Cadence DE-HDL packaged netlist, KiCad conversion of 04192023_DAF0TMB3IC0_F0TG_MB_C_brd_V02_OCP.brd

R1066  Q_RES  4.7K 5% EMPTY  pkg 0201LF  page 298 : A = P1V8_CPU0_RT_1D ; B = JTAG_TEST_MODE_RT_CPU0_P2
R1179  Q_RES  0 5% CHIP  pkg 0402LF  page 80 : A = FM_OCP_V3_2_AUX_PWR_R_EN ; B = FM_OCP_V3_2_AUX_PWR_EN
R1466  Q_RES  1K 1% EMPTY  pkg 0201LF  page 320 : A = P1V8_CPU1_RT_1D ; B = JTAG_TDO_RT_CPU1_P0

(kicad_pcb
	(version 20260206)
	(generator "pcbnew")
	(generator_version "10.0")
	(general
		(thickness 1.6)
		(legacy_teardrops no)
	)
	(paper "A4")
	(title_block
		(title "04192023_DAF0TMB3IC0_F0TG_MB_C_brd_V02_OCP.brd")
		(comment 1 "Grand Teton / footprints 3462-3464 of 8354")
	)
	(layers
		(0 "F.Cu" signal "TOP")
		(4 "In1.Cu" signal "GND")
		(6 "In2.Cu" signal "IN1")
		(8 "In3.Cu" signal "GND1")
		(10 "In4.Cu" signal "IN2")
		(12 "In5.Cu" signal "GND2")
		(14 "In6.Cu" signal "IN3")
		(16 "In7.Cu" signal "GND3")
		(18 "In8.Cu" signal "VCC")
		(20 "In9.Cu" signal "VCC1")
		(22 "In10.Cu" signal "GND4")
		(24 "In11.Cu" signal "IN4")
		(26 "In12.Cu" signal "GND5")
		(28 "In13.Cu" signal "IN5")
		(30 "In14.Cu" signal "GND6")
		(32 "In15.Cu" signal "IN6")
		(34 "In16.Cu" signal "GND7")
		(2 "B.Cu" signal "BOTTOM")
		(9 "F.Adhes" user "F.Adhesive")
		(11 "B.Adhes" user "B.Adhesive")
		(13 "F.Paste" user "Package Geometry/Pastemask Top")
		(15 "B.Paste" user "Package Geometry/Pastemask Bottom")
		(5 "F.SilkS" user "Ref Des/Silkscreen Top")
		(7 "B.SilkS" user "Ref Des/Silkscreen Bottom")
		(1 "F.Mask" user "Board Geometry/Soldermask Top")
		(3 "B.Mask" user "Board Geometry/Soldermask Bottom")
		(17 "Dwgs.User" user "User.Drawings")
		(19 "Cmts.User" user "User.Comments")
		(21 "Eco1.User" user "User.Eco1")
		(23 "Eco2.User" user "User.Eco2")
		(25 "Edge.Cuts" user "Board Geometry/Outline")
		(27 "Margin" user)
		(31 "F.CrtYd" user "Package Geometry/Place Bound Top")
		(29 "B.CrtYd" user "Package Geometry/Place Bound Bottom")
		(35 "F.Fab" user "Ref Des/Assembly Top")
		(33 "B.Fab" user "Ref Des/Assembly Bottom")
	)
	(footprint ""
		(layer "F.Cu")
		(at 66.929 -55.245 180)
		(property "Reference" "R1179"
			(at 0 0 180)
			(layer "F.SilkS")
			(hide yes)
			(effects
				(font
					(size 1.27 1.27)
				)
			)
		)
		(property "Value" ""
			(at 0 0 180)
			(layer "F.Fab")
			(effects
				(font
					(size 1.27 1.27)
				)
			)
		)
		(duplicate_pad_numbers_are_jumpers no)
		(fp_line
			(start 0.7874 0.4064)
			(end -0.7874 0.4064)
			(stroke
				(width 0.1524)
				(type default)
			)
			(layer "F.SilkS")
		)
		(fp_line
			(start 0.7874 -0.4064)
			(end 0.7874 0.4064)
			(stroke
				(width 0.1524)
				(type default)
			)
			(layer "F.SilkS")
		)
		(fp_line
			(start -0.7874 0.4064)
			(end -0.7874 -0.4064)
			(stroke
				(width 0.1524)
				(type default)
			)
			(layer "F.SilkS")
		)
		(fp_line
			(start -0.7874 -0.4064)
			(end 0.7874 -0.4064)
			(stroke
				(width 0.1524)
				(type default)
			)
			(layer "F.SilkS")
		)
		(fp_line
			(start 0.67945 0.3048)
			(end 0.120396 0.3048)
			(stroke
				(width 0.1)
				(type default)
			)
			(layer "F.Fab")
		)
		(fp_line
			(start 0.67945 -0.3048)
			(end 0.67945 0.3048)
			(stroke
				(width 0.1)
				(type default)
			)
			(layer "F.Fab")
		)
		(fp_line
			(start 0.12065 -0.2794)
			(end 0.12065 -0.3048)
			(stroke
				(width 0.1)
				(type default)
			)
			(layer "F.Fab")
		)
		(fp_line
			(start 0.12065 -0.3048)
			(end 0.67945 -0.3048)
			(stroke
				(width 0.1)
				(type default)
			)
			(layer "F.Fab")
		)
		(fp_line
			(start 0.120396 0.3048)
			(end 0.120396 0.2794)
			(stroke
				(width 0.1)
				(type default)
			)
			(layer "F.Fab")
		)
		(fp_line
			(start 0.120396 0.2794)
			(end -0.12065 0.2794)
			(stroke
				(width 0.1)
				(type default)
			)
			(layer "F.Fab")
		)
		(fp_line
			(start -0.12065 0.3048)
			(end -0.67945 0.3048)
			(stroke
				(width 0.1)
				(type default)
			)
			(layer "F.Fab")
		)
		(fp_line
			(start -0.12065 0.2794)
			(end -0.12065 0.3048)
			(stroke
				(width 0.1)
				(type default)
			)
			(layer "F.Fab")
		)
		(fp_line
			(start -0.12065 -0.2794)
			(end 0.12065 -0.2794)
			(stroke
				(width 0.1)
				(type default)
			)
			(layer "F.Fab")
		)
		(fp_line
			(start -0.12065 -0.305054)
			(end -0.12065 -0.2794)
			(stroke
				(width 0.1)
				(type default)
			)
			(layer "F.Fab")
		)
		(fp_line
			(start -0.67945 0.3048)
			(end -0.67945 -0.305054)
			(stroke
				(width 0.1)
				(type default)
			)
			(layer "F.Fab")
		)
		(fp_line
			(start -0.67945 -0.305054)
			(end -0.12065 -0.305054)
			(stroke
				(width 0.1)
				(type default)
			)
			(layer "F.Fab")
		)
		(pad "1" smd circle
			(at -0.40005 0 180)
			(size 0 0)
			(layers "F.Cu" "F.Mask" "F.Paste")
			(net "FM_OCP_V3_2_AUX_PWR_R_EN")
		)
		(pad "2" smd circle
			(at 0.40005 0 180)
			(size 0 0)
			(layers "F.Cu" "F.Mask" "F.Paste")
			(net "FM_OCP_V3_2_AUX_PWR_EN")
		)
	)
	(footprint ""
		(layer "F.Cu")
		(at 402.214842 -404.873206 -90)
		(property "Reference" "R1066"
			(at 0 0 270)
			(layer "F.SilkS")
			(hide yes)
			(effects
				(font
					(size 1.27 1.27)
				)
			)
		)
		(property "Value" ""
			(at 0 0 270)
			(layer "F.Fab")
			(effects
				(font
					(size 1.27 1.27)
				)
			)
		)
		(duplicate_pad_numbers_are_jumpers no)
		(fp_line
			(start -0.32512 0.175006)
			(end -0.32512 -0.175006)
			(stroke
				(width 0.1)
				(type default)
			)
			(layer "F.Fab")
		)
		(fp_line
			(start 0.32512 0.175006)
			(end -0.32512 0.175006)
			(stroke
				(width 0.1)
				(type default)
			)
			(layer "F.Fab")
		)
		(fp_line
			(start -0.32512 -0.175006)
			(end 0.32512 -0.175006)
			(stroke
				(width 0.1)
				(type default)
			)
			(layer "F.Fab")
		)
		(fp_line
			(start 0.32512 -0.175006)
			(end 0.32512 0.175006)
			(stroke
				(width 0.1)
				(type default)
			)
			(layer "F.Fab")
		)
		(pad "1" smd rect
			(at -0.2667 0 270)
			(size 0.3048 0.381)
			(layers "F.Cu" "F.Mask" "F.Paste")
			(net "P1V8_CPU0_RT_1D")
		)
		(pad "2" smd rect
			(at 0.2667 0 90)
			(size 0.3048 0.381)
			(layers "F.Cu" "F.Mask" "F.Paste")
			(net "JTAG_TEST_MODE_RT_CPU0_P2")
		)
	)
	(footprint ""
		(layer "F.Cu")
		(at 45.932344 -419.700964)
		(property "Reference" "R1466"
			(at 0 0 0)
			(layer "F.SilkS")
			(hide yes)
			(effects
				(font
					(size 1.27 1.27)
				)
			)
		)
		(property "Value" ""
			(at 0 0 0)
			(layer "F.Fab")
			(effects
				(font
					(size 1.27 1.27)
				)
			)
		)
		(duplicate_pad_numbers_are_jumpers no)
		(fp_line
			(start -0.32512 -0.175006)
			(end 0.32512 -0.175006)
			(stroke
				(width 0.1)
				(type default)
			)
			(layer "F.Fab")
		)
		(fp_line
			(start -0.32512 0.175006)
			(end -0.32512 -0.175006)
			(stroke
				(width 0.1)
				(type default)
			)
			(layer "F.Fab")
		)
		(fp_line
			(start 0.32512 -0.175006)
			(end 0.32512 0.175006)
			(stroke
				(width 0.1)
				(type default)
			)
			(layer "F.Fab")
		)
		(fp_line
			(start 0.32512 0.175006)
			(end -0.32512 0.175006)
			(stroke
				(width 0.1)
				(type default)
			)
			(layer "F.Fab")
		)
		(pad "1" smd rect
			(at -0.2667 0)
			(size 0.3048 0.381)
			(layers "F.Cu" "F.Mask" "F.Paste")
			(net "P1V8_CPU1_RT_1D")
		)
		(pad "2" smd rect
			(at 0.2667 0 180)
			(size 0.3048 0.381)
			(layers "F.Cu" "F.Mask" "F.Paste")
			(net "JTAG_TDO_RT_CPU1_P0")
		)
	)
)
